(kicad_pcb
	(version 20260206)
	(generator "pcbnew")
	(generator_version "10.0")
	(general
		(thickness 1.6)
		(legacy_teardrops no)
	)
	(paper "A4")
	(title_block
		(title "01162023_DA0F0TEBIF0_F0T_Expander_BD_F_brd_V02_OCP.brd")
		(comment 1 "Grand Teton / footprints 6430-6436 of 9728")
	)
	(layers
		(0 "F.Cu" signal "TOP")
		(4 "In1.Cu" signal "GND")
		(6 "In2.Cu" signal "VCC")
		(8 "In3.Cu" signal "VCC1")
		(10 "In4.Cu" signal "GND1")
		(12 "In5.Cu" signal "IN1")
		(14 "In6.Cu" signal "GND2")
		(16 "In7.Cu" signal "IN2")
		(18 "In8.Cu" signal "GND3")
		(20 "In9.Cu" signal "IN3")
		(22 "In10.Cu" signal "GND4")
		(24 "In11.Cu" signal "IN4")
		(26 "In12.Cu" signal "GND5")
		(28 "In13.Cu" signal "IN5")
		(30 "In14.Cu" signal "GND6")
		(32 "In15.Cu" signal "IN6")
		(34 "In16.Cu" signal "GND7")
		(2 "B.Cu" signal "BOTTOM")
		(9 "F.Adhes" user "F.Adhesive")
		(11 "B.Adhes" user "B.Adhesive")
		(13 "F.Paste" user "Package Geometry/Pastemask Top")
		(15 "B.Paste" user "Package Geometry/Pastemask Bottom")
		(5 "F.SilkS" user "Ref Des/Silkscreen Top")
		(7 "B.SilkS" user "Ref Des/Silkscreen Bottom")
		(1 "F.Mask" user "Board Geometry/Soldermask Top")
		(3 "B.Mask" user "Board Geometry/Soldermask Bottom")
		(17 "Dwgs.User" user "User.Drawings")
		(19 "Cmts.User" user "User.Comments")
		(21 "Eco1.User" user "User.Eco1")
		(23 "Eco2.User" user "User.Eco2")
		(25 "Edge.Cuts" user "Board Geometry/Outline")
		(27 "Margin" user)
		(31 "F.CrtYd" user "Package Geometry/Place Bound Top")
		(29 "B.CrtYd" user "Package Geometry/Place Bound Bottom")
		(35 "F.Fab" user "Ref Des/Assembly Top")
		(33 "B.Fab" user "Ref Des/Assembly Bottom")
	)
	(footprint ""
		(layer "F.Cu")
		(at 239.971834 -24.807418)
		(property "Reference" "R435"
			(at 0 0 0)
			(layer "F.SilkS")
			(hide yes)
			(effects
				(font
					(size 1.27 1.27)
				)
			)
		)
		(property "Value" ""
			(at 0 0 0)
			(layer "F.Fab")
			(effects
				(font
					(size 1.27 1.27)
				)
			)
		)
		(duplicate_pad_numbers_are_jumpers no)
		(fp_line
			(start -0.7874 -0.4064)
			(end 0.7874 -0.4064)
			(stroke
				(width 0.1524)
				(type default)
			)
			(layer "F.SilkS")
		)
		(fp_line
			(start -0.7874 0.4064)
			(end -0.7874 -0.4064)
			(stroke
				(width 0.1524)
				(type default)
			)
			(layer "F.SilkS")
		)
		(fp_line
			(start 0.7874 -0.4064)
			(end 0.7874 0.4064)
			(stroke
				(width 0.1524)
				(type default)
			)
			(layer "F.SilkS")
		)
		(fp_line
			(start 0.7874 0.4064)
			(end -0.7874 0.4064)
			(stroke
				(width 0.1524)
				(type default)
			)
			(layer "F.SilkS")
		)
		(fp_line
			(start -0.67945 -0.305054)
			(end -0.12065 -0.305054)
			(stroke
				(width 0.1)
				(type default)
			)
			(layer "F.Fab")
		)
		(fp_line
			(start -0.67945 0.3048)
			(end -0.67945 -0.305054)
			(stroke
				(width 0.1)
				(type default)
			)
			(layer "F.Fab")
		)
		(fp_line
			(start -0.12065 -0.305054)
			(end -0.12065 -0.2794)
			(stroke
				(width 0.1)
				(type default)
			)
			(layer "F.Fab")
		)
		(fp_line
			(start -0.12065 -0.2794)
			(end 0.12065 -0.2794)
			(stroke
				(width 0.1)
				(type default)
			)
			(layer "F.Fab")
		)
		(fp_line
			(start -0.12065 0.2794)
			(end -0.12065 0.3048)
			(stroke
				(width 0.1)
				(type default)
			)
			(layer "F.Fab")
		)
		(fp_line
			(start -0.12065 0.3048)
			(end -0.67945 0.3048)
			(stroke
				(width 0.1)
				(type default)
			)
			(layer "F.Fab")
		)
		(fp_line
			(start 0.120396 0.2794)
			(end -0.12065 0.2794)
			(stroke
				(width 0.1)
				(type default)
			)
			(layer "F.Fab")
		)
		(fp_line
			(start 0.120396 0.3048)
			(end 0.120396 0.2794)
			(stroke
				(width 0.1)
				(type default)
			)
			(layer "F.Fab")
		)
		(fp_line
			(start 0.12065 -0.3048)
			(end 0.67945 -0.3048)
			(stroke
				(width 0.1)
				(type default)
			)
			(layer "F.Fab")
		)
		(fp_line
			(start 0.12065 -0.2794)
			(end 0.12065 -0.3048)
			(stroke
				(width 0.1)
				(type default)
			)
			(layer "F.Fab")
		)
		(fp_line
			(start 0.67945 -0.3048)
			(end 0.67945 0.3048)
			(stroke
				(width 0.1)
				(type default)
			)
			(layer "F.Fab")
		)
		(fp_line
			(start 0.67945 0.3048)
			(end 0.120396 0.3048)
			(stroke
				(width 0.1)
				(type default)
			)
			(layer "F.Fab")
		)
		(pad "1" smd circle
			(at -0.40005 0)
			(size 0 0)
			(layers "F.Cu" "F.Mask" "F.Paste")
			(net "P3V3_SSD8")
		)
		(pad "2" smd circle
			(at 0.40005 0)
			(size 0 0)
			(layers "F.Cu" "F.Mask" "F.Paste")
			(net "PU_CLKREQ8")
		)
	)
	(footprint ""
		(layer "F.Cu")
		(at 317.957708 -299.04055 -90)
		(property "Reference" "C4187"
			(at 0 0 270)
			(layer "F.SilkS")
			(hide yes)
			(effects
				(font
					(size 1.27 1.27)
				)
			)
		)
		(property "Value" ""
			(at 0 0 270)
			(layer "F.Fab")
			(effects
				(font
					(size 1.27 1.27)
				)
			)
		)
		(duplicate_pad_numbers_are_jumpers no)
		(fp_line
			(start -0.7874 0.4064)
			(end -0.7874 -0.4064)
			(stroke
				(width 0.1524)
				(type default)
			)
			(layer "F.SilkS")
		)
		(fp_line
			(start 0.7874 0.4064)
			(end -0.7874 0.4064)
			(stroke
				(width 0.1524)
				(type default)
			)
			(layer "F.SilkS")
		)
		(fp_line
			(start -0.7874 -0.4064)
			(end 0.7874 -0.4064)
			(stroke
				(width 0.1524)
				(type default)
			)
			(layer "F.SilkS")
		)
		(fp_line
			(start 0.7874 -0.4064)
			(end 0.7874 0.4064)
			(stroke
				(width 0.1524)
				(type default)
			)
			(layer "F.SilkS")
		)
		(fp_line
			(start -0.67945 0.3048)
			(end -0.67945 -0.305054)
			(stroke
				(width 0.1)
				(type default)
			)
			(layer "F.Fab")
		)
		(fp_line
			(start -0.12065 0.3048)
			(end -0.67945 0.3048)
			(stroke
				(width 0.1)
				(type default)
			)
			(layer "F.Fab")
		)
		(fp_line
			(start 0.120396 0.3048)
			(end 0.120396 0.2794)
			(stroke
				(width 0.1)
				(type default)
			)
			(layer "F.Fab")
		)
		(fp_line
			(start 0.67945 0.3048)
			(end 0.120396 0.3048)
			(stroke
				(width 0.1)
				(type default)
			)
			(layer "F.Fab")
		)
		(fp_line
			(start -0.12065 0.2794)
			(end -0.12065 0.3048)
			(stroke
				(width 0.1)
				(type default)
			)
			(layer "F.Fab")
		)
		(fp_line
			(start 0.120396 0.2794)
			(end -0.12065 0.2794)
			(stroke
				(width 0.1)
				(type default)
			)
			(layer "F.Fab")
		)
		(fp_line
			(start -0.12065 -0.2794)
			(end 0.12065 -0.2794)
			(stroke
				(width 0.1)
				(type default)
			)
			(layer "F.Fab")
		)
		(fp_line
			(start 0.12065 -0.2794)
			(end 0.12065 -0.3048)
			(stroke
				(width 0.1)
				(type default)
			)
			(layer "F.Fab")
		)
		(fp_line
			(start 0.12065 -0.3048)
			(end 0.67945 -0.3048)
			(stroke
				(width 0.1)
				(type default)
			)
			(layer "F.Fab")
		)
		(fp_line
			(start 0.67945 -0.3048)
			(end 0.67945 0.3048)
			(stroke
				(width 0.1)
				(type default)
			)
			(layer "F.Fab")
		)
		(fp_line
			(start -0.67945 -0.305054)
			(end -0.12065 -0.305054)
			(stroke
				(width 0.1)
				(type default)
			)
			(layer "F.Fab")
		)
		(fp_line
			(start -0.12065 -0.305054)
			(end -0.12065 -0.2794)
			(stroke
				(width 0.1)
				(type default)
			)
			(layer "F.Fab")
		)
		(pad "1" smd circle
			(at -0.40005 0 270)
			(size 0 0)
			(layers "F.Cu" "F.Mask" "F.Paste")
			(net "GND")
		)
		(pad "2" smd circle
			(at 0.40005 0 270)
			(size 0 0)
			(layers "F.Cu" "F.Mask" "F.Paste")
			(net "P1V8_PEX")
		)
	)
	(footprint ""
		(layer "F.Cu")
		(at 8.549386 -255.046734 -90)
		(property "Reference" "R6462"
			(at 0 0 270)
			(layer "F.SilkS")
			(hide yes)
			(effects
				(font
					(size 1.27 1.27)
				)
			)
		)
		(property "Value" ""
			(at 0 0 270)
			(layer "F.Fab")
			(effects
				(font
					(size 1.27 1.27)
				)
			)
		)
		(duplicate_pad_numbers_are_jumpers no)
		(fp_line
			(start -0.7874 0.4064)
			(end -0.7874 -0.4064)
			(stroke
				(width 0.1524)
				(type default)
			)
			(layer "F.SilkS")
		)
		(fp_line
			(start 0.7874 0.4064)
			(end -0.7874 0.4064)
			(stroke
				(width 0.1524)
				(type default)
			)
			(layer "F.SilkS")
		)
		(fp_line
			(start -0.7874 -0.4064)
			(end 0.7874 -0.4064)
			(stroke
				(width 0.1524)
				(type default)
			)
			(layer "F.SilkS")
		)
		(fp_line
			(start 0.7874 -0.4064)
			(end 0.7874 0.4064)
			(stroke
				(width 0.1524)
				(type default)
			)
			(layer "F.SilkS")
		)
		(fp_line
			(start -0.67945 0.3048)
			(end -0.67945 -0.305054)
			(stroke
				(width 0.1)
				(type default)
			)
			(layer "F.Fab")
		)
		(fp_line
			(start -0.12065 0.3048)
			(end -0.67945 0.3048)
			(stroke
				(width 0.1)
				(type default)
			)
			(layer "F.Fab")
		)
		(fp_line
			(start 0.120396 0.3048)
			(end 0.120396 0.2794)
			(stroke
				(width 0.1)
				(type default)
			)
			(layer "F.Fab")
		)
		(fp_line
			(start 0.67945 0.3048)
			(end 0.120396 0.3048)
			(stroke
				(width 0.1)
				(type default)
			)
			(layer "F.Fab")
		)
		(fp_line
			(start -0.12065 0.2794)
			(end -0.12065 0.3048)
			(stroke
				(width 0.1)
				(type default)
			)
			(layer "F.Fab")
		)
		(fp_line
			(start 0.120396 0.2794)
			(end -0.12065 0.2794)
			(stroke
				(width 0.1)
				(type default)
			)
			(layer "F.Fab")
		)
		(fp_line
			(start -0.12065 -0.2794)
			(end 0.12065 -0.2794)
			(stroke
				(width 0.1)
				(type default)
			)
			(layer "F.Fab")
		)
		(fp_line
			(start 0.12065 -0.2794)
			(end 0.12065 -0.3048)
			(stroke
				(width 0.1)
				(type default)
			)
			(layer "F.Fab")
		)
		(fp_line
			(start 0.12065 -0.3048)
			(end 0.67945 -0.3048)
			(stroke
				(width 0.1)
				(type default)
			)
			(layer "F.Fab")
		)
		(fp_line
			(start 0.67945 -0.3048)
			(end 0.67945 0.3048)
			(stroke
				(width 0.1)
				(type default)
			)
			(layer "F.Fab")
		)
		(fp_line
			(start -0.67945 -0.305054)
			(end -0.12065 -0.305054)
			(stroke
				(width 0.1)
				(type default)
			)
			(layer "F.Fab")
		)
		(fp_line
			(start -0.12065 -0.305054)
			(end -0.12065 -0.2794)
			(stroke
				(width 0.1)
				(type default)
			)
			(layer "F.Fab")
		)
		(pad "1" smd circle
			(at -0.40005 0 270)
			(size 0 0)
			(layers "F.Cu" "F.Mask" "F.Paste")
			(net "P1V25_SERDES_VDDPLL_PEX0")
		)
		(pad "2" smd circle
			(at 0.40005 0 270)
			(size 0 0)
			(layers "F.Cu" "F.Mask" "F.Paste")
			(net "P1V25_SERDES_VDDPLL_PEX0_C1")
		)
	)
	(footprint ""
		(layer "F.Cu")
		(at 19.307048 -343.952322 90)
		(property "Reference" "C2152"
			(at 0 0 90)
			(layer "F.SilkS")
			(hide yes)
			(effects
				(font
					(size 1.27 1.27)
				)
			)
		)
		(property "Value" ""
			(at 0 0 90)
			(layer "F.Fab")
			(effects
				(font
					(size 1.27 1.27)
				)
			)
		)
		(duplicate_pad_numbers_are_jumpers no)
		(fp_line
			(start 0.299974 -0.150114)
			(end 0.299974 0.150114)
			(stroke
				(width 0.1)
				(type default)
			)
			(layer "F.Fab")
		)
		(fp_line
			(start -0.299974 -0.150114)
			(end 0.299974 -0.150114)
			(stroke
				(width 0.1)
				(type default)
			)
			(layer "F.Fab")
		)
		(fp_line
			(start 0.299974 0.150114)
			(end -0.299974 0.150114)
			(stroke
				(width 0.1)
				(type default)
			)
			(layer "F.Fab")
		)
		(fp_line
			(start -0.299974 0.150114)
			(end -0.299974 -0.150114)
			(stroke
				(width 0.1)
				(type default)
			)
			(layer "F.Fab")
		)
		(pad "1" smd rect
			(at -0.2667 0 90)
			(size 0.3048 0.381)
			(layers "F.Cu" "F.Mask" "F.Paste")
			(net "P5E_PEX0_STN4_TX_DP<79>")
		)
		(pad "2" smd rect
			(at 0.2667 0 90)
			(size 0.3048 0.381)
			(layers "F.Cu" "F.Mask" "F.Paste")
			(net "P5E_PEX0_STN4_TX_C_DP<79>")
		)
	)
	(footprint ""
		(layer "F.Cu")
		(at 75.65644 -20.467574 180)
		(property "Reference" "R1647"
			(at 0 0 180)
			(layer "F.SilkS")
			(hide yes)
			(effects
				(font
					(size 1.27 1.27)
				)
			)
		)
		(property "Value" ""
			(at 0 0 180)
			(layer "F.Fab")
			(effects
				(font
					(size 1.27 1.27)
				)
			)
		)
		(duplicate_pad_numbers_are_jumpers no)
		(fp_line
			(start 0.7874 0.4064)
			(end -0.7874 0.4064)
			(stroke
				(width 0.1524)
				(type default)
			)
			(layer "F.SilkS")
		)
		(fp_line
			(start 0.7874 -0.4064)
			(end 0.7874 0.4064)
			(stroke
				(width 0.1524)
				(type default)
			)
			(layer "F.SilkS")
		)
		(fp_line
			(start -0.7874 0.4064)
			(end -0.7874 -0.4064)
			(stroke
				(width 0.1524)
				(type default)
			)
			(layer "F.SilkS")
		)
		(fp_line
			(start -0.7874 -0.4064)
			(end 0.7874 -0.4064)
			(stroke
				(width 0.1524)
				(type default)
			)
			(layer "F.SilkS")
		)
		(fp_line
			(start 0.67945 0.3048)
			(end 0.120396 0.3048)
			(stroke
				(width 0.1)
				(type default)
			)
			(layer "F.Fab")
		)
		(fp_line
			(start 0.67945 -0.3048)
			(end 0.67945 0.3048)
			(stroke
				(width 0.1)
				(type default)
			)
			(layer "F.Fab")
		)
		(fp_line
			(start 0.12065 -0.2794)
			(end 0.12065 -0.3048)
			(stroke
				(width 0.1)
				(type default)
			)
			(layer "F.Fab")
		)
		(fp_line
			(start 0.12065 -0.3048)
			(end 0.67945 -0.3048)
			(stroke
				(width 0.1)
				(type default)
			)
			(layer "F.Fab")
		)
		(fp_line
			(start 0.120396 0.3048)
			(end 0.120396 0.2794)
			(stroke
				(width 0.1)
				(type default)
			)
			(layer "F.Fab")
		)
		(fp_line
			(start 0.120396 0.2794)
			(end -0.12065 0.2794)
			(stroke
				(width 0.1)
				(type default)
			)
			(layer "F.Fab")
		)
		(fp_line
			(start -0.12065 0.3048)
			(end -0.67945 0.3048)
			(stroke
				(width 0.1)
				(type default)
			)
			(layer "F.Fab")
		)
		(fp_line
			(start -0.12065 0.2794)
			(end -0.12065 0.3048)
			(stroke
				(width 0.1)
				(type default)
			)
			(layer "F.Fab")
		)
		(fp_line
			(start -0.12065 -0.2794)
			(end 0.12065 -0.2794)
			(stroke
				(width 0.1)
				(type default)
			)
			(layer "F.Fab")
		)
		(fp_line
			(start -0.12065 -0.305054)
			(end -0.12065 -0.2794)
			(stroke
				(width 0.1)
				(type default)
			)
			(layer "F.Fab")
		)
		(fp_line
			(start -0.67945 0.3048)
			(end -0.67945 -0.305054)
			(stroke
				(width 0.1)
				(type default)
			)
			(layer "F.Fab")
		)
		(fp_line
			(start -0.67945 -0.305054)
			(end -0.12065 -0.305054)
			(stroke
				(width 0.1)
				(type default)
			)
			(layer "F.Fab")
		)
		(pad "1" smd circle
			(at -0.40005 0 180)
			(size 0 0)
			(layers "F.Cu" "F.Mask" "F.Paste")
			(net "P3V3_SSD2")
		)
		(pad "2" smd circle
			(at 0.40005 0 180)
			(size 0 0)
			(layers "F.Cu" "F.Mask" "F.Paste")
			(net "SMB_ISO_SSD2_SDA")
		)
	)
	(footprint ""
		(layer "F.Cu")
		(at 358.013 -228.6 180)
		(property "Reference" "R3640"
			(at 0 0 180)
			(layer "F.SilkS")
			(hide yes)
			(effects
				(font
					(size 1.27 1.27)
				)
			)
		)
		(property "Value" ""
			(at 0 0 180)
			(layer "F.Fab")
			(effects
				(font
					(size 1.27 1.27)
				)
			)
		)
		(duplicate_pad_numbers_are_jumpers no)
		(fp_line
			(start 0.7874 0.4064)
			(end -0.7874 0.4064)
			(stroke
				(width 0.1524)
				(type default)
			)
			(layer "F.SilkS")
		)
		(fp_line
			(start 0.7874 -0.4064)
			(end 0.7874 0.4064)
			(stroke
				(width 0.1524)
				(type default)
			)
			(layer "F.SilkS")
		)
		(fp_line
			(start -0.7874 0.4064)
			(end -0.7874 -0.4064)
			(stroke
				(width 0.1524)
				(type default)
			)
			(layer "F.SilkS")
		)
		(fp_line
			(start -0.7874 -0.4064)
			(end 0.7874 -0.4064)
			(stroke
				(width 0.1524)
				(type default)
			)
			(layer "F.SilkS")
		)
		(fp_line
			(start 0.67945 0.3048)
			(end 0.120396 0.3048)
			(stroke
				(width 0.1)
				(type default)
			)
			(layer "F.Fab")
		)
		(fp_line
			(start 0.67945 -0.3048)
			(end 0.67945 0.3048)
			(stroke
				(width 0.1)
				(type default)
			)
			(layer "F.Fab")
		)
		(fp_line
			(start 0.12065 -0.2794)
			(end 0.12065 -0.3048)
			(stroke
				(width 0.1)
				(type default)
			)
			(layer "F.Fab")
		)
		(fp_line
			(start 0.12065 -0.3048)
			(end 0.67945 -0.3048)
			(stroke
				(width 0.1)
				(type default)
			)
			(layer "F.Fab")
		)
		(fp_line
			(start 0.120396 0.3048)
			(end 0.120396 0.2794)
			(stroke
				(width 0.1)
				(type default)
			)
			(layer "F.Fab")
		)
		(fp_line
			(start 0.120396 0.2794)
			(end -0.12065 0.2794)
			(stroke
				(width 0.1)
				(type default)
			)
			(layer "F.Fab")
		)
		(fp_line
			(start -0.12065 0.3048)
			(end -0.67945 0.3048)
			(stroke
				(width 0.1)
				(type default)
			)
			(layer "F.Fab")
		)
		(fp_line
			(start -0.12065 0.2794)
			(end -0.12065 0.3048)
			(stroke
				(width 0.1)
				(type default)
			)
			(layer "F.Fab")
		)
		(fp_line
			(start -0.12065 -0.2794)
			(end 0.12065 -0.2794)
			(stroke
				(width 0.1)
				(type default)
			)
			(layer "F.Fab")
		)
		(fp_line
			(start -0.12065 -0.305054)
			(end -0.12065 -0.2794)
			(stroke
				(width 0.1)
				(type default)
			)
			(layer "F.Fab")
		)
		(fp_line
			(start -0.67945 0.3048)
			(end -0.67945 -0.305054)
			(stroke
				(width 0.1)
				(type default)
			)
			(layer "F.Fab")
		)
		(fp_line
			(start -0.67945 -0.305054)
			(end -0.12065 -0.305054)
			(stroke
				(width 0.1)
				(type default)
			)
			(layer "F.Fab")
		)
		(pad "1" smd circle
			(at -0.40005 0 180)
			(size 0 0)
			(layers "F.Cu" "F.Mask" "F.Paste")
			(net "NIC4_CLK_EN_R_N")
		)
		(pad "2" smd circle
			(at 0.40005 0 180)
			(size 0 0)
			(layers "F.Cu" "F.Mask" "F.Paste")
			(net "NIC4_CLK_EN_N")
		)
	)
	(footprint ""
		(layer "F.Cu")
		(at 249.992388 -29.139642 180)
		(property "Reference" "C493"
			(at 0 0 180)
			(layer "F.SilkS")
			(hide yes)
			(effects
				(font
					(size 1.27 1.27)
				)
			)
		)
		(property "Value" ""
			(at 0 0 180)
			(layer "F.Fab")
			(effects
				(font
					(size 1.27 1.27)
				)
			)
		)
		(duplicate_pad_numbers_are_jumpers no)
		(fp_line
			(start 0.299974 0.150114)
			(end -0.299974 0.150114)
			(stroke
				(width 0.1)
				(type default)
			)
			(layer "F.Fab")
		)
		(fp_line
			(start 0.299974 -0.150114)
			(end 0.299974 0.150114)
			(stroke
				(width 0.1)
				(type default)
			)
			(layer "F.Fab")
		)
		(fp_line
			(start -0.299974 0.150114)
			(end -0.299974 -0.150114)
			(stroke
				(width 0.1)
				(type default)
			)
			(layer "F.Fab")
		)
		(fp_line
			(start -0.299974 -0.150114)
			(end 0.299974 -0.150114)
			(stroke
				(width 0.1)
				(type default)
			)
			(layer "F.Fab")
		)
		(pad "1" smd rect
			(at -0.2667 0 180)
			(size 0.3048 0.381)
			(layers "F.Cu" "F.Mask" "F.Paste")
			(net "P5E_PEX2_STN2_TX_DP<44>")
		)
		(pad "2" smd rect
			(at 0.2667 0 180)
			(size 0.3048 0.381)
			(layers "F.Cu" "F.Mask" "F.Paste")
			(net "P5E_PEX2_STN2_TX_C_DP<44>")
		)
	)
)
